FILE_TYPE = CONNECTIVITY;
{Allegro Design Entry HDL 16.6-p007 (v16-6-112F) 10/10/2012}
"PAGE_NUMBER" = 188;
0"NC";
1"P3V3_STBY\g";
2"GND\g";
3"GND\g";
4"GND\g";
5"GND\g";
6"P12V_STBY\g";
7"P12V_STBY\g";
8"P12V_STBY\g";
9"P12V_STBY\g";
10"P12V_STBY\g";
11"FM_GBE3_LVC3_MOD_ABS";
12"LED_GBE_P3_0";
13"LED_GBE_P3_1";
14"SMB_PCH_MEZZ_LOM2_SDA";
15"KR_P0_OCP_RX_DP";
16"FM_GBE2_LVC3_MOD_ABS";
17"FM_GBE1_LVC3_MOD_ABS";
18"FM_GBE0_LVC3_MOD_ABS";
19"EXT_MDIO_I2C_SEL";
20"FM_GBE3_LVC3_MOD_ABS";
21"SMB_PCH_MEZZ_LOM0_SDA";
22"SMB_PCH_MEZZ_LOM1_SDA";
23"KR_P0_OCP_RX_DP";
24"KR_P0_OCP_RX_DN";
25"KR_P1_OCP_RX_DP";
26"KR_P1_OCP_RX_DN";
27"SMB_PCH_MEZZ_LOM3_SDA";
28"FM_GBE2_LVC3_MOD_ABS";
29"FM_OCP_MEZZC_PRES_N";
30"TP_SHARED_KR_MDIO_0";
31"TP_SHARED_KR_MDC_0";
32"LED_GBE_P2_1";
33"LED_GBE_P2_0";
34"SMB_PCH_MEZZ_LOM2_SCL";
35"SMB_OCP_FRU_STBY_LVC3_SDA";
36"SMB_OCP_FRU_STBY_LVC3_SCL";
37"SMB_PCH_MEZZ_LOM2_SCL";
38"SMB_PCH_MEZZ_LOM0_SCL";
39"SMB_PCH_MEZZ_LOM1_SCL";
40"SMB_PCH_MEZZ_LOM3_SCL";
41"FM_GBE0_LVC3_MOD_ABS";
42"FM_GBE1_LVC3_MOD_ABS";
43"KR_P0_OCP_TX_DP";
44"KR_P0_OCP_TX_DN";
45"LED_GBE_P0_0";
46"LED_GBE_P0_1";
47"KR_P1_OCP_TX_DP";
48"KR_P1_OCP_TX_DN";
49"LED_GBE_P1_0";
50"LED_GBE_P1_1";
51"EXT_MDIO_I2C_SEL";
52"TP_RSVD<0>";
53"SMB_PCH_MEZZ_LOM3_SDA";
54"SMB_PCH_MEZZ_LOM3_SCL";
55"SMB_PCH_MEZZ_LOM2_SDA";
56"SMB_PCH_MEZZ_LOM0_SCL";
57"SMB_PCH_MEZZ_LOM0_SDA";
58"SMB_PCH_MEZZ_LOM1_SCL";
59"SMB_PCH_MEZZ_LOM1_SDA";
60"KR_P1_OCP_RX_C_DP";
61"KR_P1_OCP_RX_DN";
62"KR_P0_OCP_RX_C_DN";
63"KR_P0_OCP_RX_DN";
64"KR_P1_OCP_RX_DP";
65"KR_P1_OCP_RX_C_DN";
66"KR_P0_OCP_RX_C_DP";
%"P3V3_STBY"
"1","(-3500,4200)","0","mstr_symbols","I116";
;
HDL_POWER"P3V3_STBY"
BODY_TYPE"PLUMBING"
SIZE"1B"
CDS_LIB"mstr_symbols"
VOLTAGE"3.3V";
"G\NAC"1;
%"CAP_A"
"2","(3075,3375)","0","dev_discrete","I120";
;
CDS_LOCATION"C8C13"
VOLTAGE"16V"
MATERIAL"X7R"
PACK_TYPE"0402V"
LOCATION"C8C13"
TOLERANCE"10%"
VALUE"0.1UF"
PART_NUMBER"A36096-030"
SEC"1"
SEC_TYPE"0402V"
CDS_SEC"1"
CDS_LIB"dev_discrete";
"A"
$PN"1"61;
"B"
$PN"2"65;
%"CAP_A"
"2","(3075,3700)","0","dev_discrete","I121";
;
CDS_LOCATION"C8C12"
LOCATION"C8C12"
VALUE"0.1UF"
VOLTAGE"16V"
PART_NUMBER"A36096-030"
PACK_TYPE"0402V"
MATERIAL"X7R"
TOLERANCE"10%"
SEC"1"
SEC_TYPE"0402V"
CDS_SEC"1"
CDS_LIB"dev_discrete";
"A"
$PN"1"64;
"B"
$PN"2"60;
%"RES"
"2","(-3250,2750)","1","mstr_discrete","I128";
;
CDS_SEC"1"
PACK_TYPE"0402"
GROUP"KR"
TOLERANCE"1%"
WATTAGE"1/16W"
LOCATION"R1W40"
VALUE"4.75K"
MATERIAL"CHIP"
PART_NUMBER"G21796-072"
CDS_LIB"mstr_discrete"
ROOM"CPU0"
SEC"1"
SEC_TYPE"0402"
CDS_LOCATION"R1W40";
"A"
$PN"1"1;
"B"
$PN"2"19;
%"RES"
"2","(-3250,2600)","1","mstr_discrete","I129";
;
CDS_SEC"1"
GROUP"KR"
POP"NOPOP"
TOLERANCE"1%"
PACK_TYPE"0402"
WATTAGE"1/16W"
VALUE"4.75K"
LOCATION"R1W41"
PART_NUMBER"G21796-072"
MATERIAL"CHIP"
CDS_LIB"mstr_discrete"
ROOM"CPU0"
SEC"1"
SEC_TYPE"0402"
CDS_LOCATION"R1W41";
"A"
$PN"1"2;
"B"
$PN"2"19;
%"GND"
"1","(-3400,2525)","0","mstr_symbols","I130";
;
VOLTAGE"0"
CDS_LIB"mstr_symbols"
SIZE"1B"
BODY_TYPE"PLUMBING"
HDL_POWER"GND";
"A\NAC"2;
%"RES"
"2","(-3250,2350)","1","mstr_discrete","I131";
;
CDS_SEC"1"
PACK_TYPE"0402"
LOCATION"R1W42"
MATERIAL"CHIP"
TOLERANCE"1%"
VALUE"4.75K"
WATTAGE"1/16W"
PART_NUMBER"G21796-072"
CDS_LIB"mstr_discrete"
ROOM"CPU0"
SEC"1"
SEC_TYPE"0402"
CDS_LOCATION"R1W42";
"A"
$PN"1"1;
"B"
$PN"2"18;
%"RES"
"2","(-3250,2200)","1","mstr_discrete","I132";
;
CDS_SEC"1"
PACK_TYPE"0402"
VALUE"4.75K"
LOCATION"R1W43"
TOLERANCE"1%"
WATTAGE"1/16W"
MATERIAL"CHIP"
PART_NUMBER"G21796-072"
SEC_TYPE"0402"
SEC"1"
ROOM"CPU0"
CDS_LIB"mstr_discrete"
CDS_LOCATION"R1W43";
"A"
$PN"1"1;
"B"
$PN"2"17;
%"RES"
"2","(-3250,2050)","1","mstr_discrete","I133";
;
CDS_SEC"1"
WATTAGE"1/16W"
PACK_TYPE"0402"
TOLERANCE"1%"
LOCATION"R1W44"
VALUE"4.75K"
PART_NUMBER"G21796-072"
MATERIAL"CHIP"
SEC_TYPE"0402"
SEC"1"
ROOM"CPU0"
CDS_LIB"mstr_discrete"
CDS_LOCATION"R1W44";
"A"
$PN"1"1;
"B"
$PN"2"16;
%"RES"
"2","(-3250,1900)","1","mstr_discrete","I134";
;
CDS_SEC"1"
PART_NUMBER"G21796-072"
PACK_TYPE"0402"
MATERIAL"CHIP"
LOCATION"R1W45"
TOLERANCE"1%"
VALUE"4.75K"
WATTAGE"1/16W"
SEC_TYPE"0402"
SEC"1"
ROOM"CPU0"
CDS_LIB"mstr_discrete"
CDS_LOCATION"R1W45";
"A"
$PN"1"1;
"B"
$PN"2"20;
%"CAP_A"
"1","(3300,1300)","0","dev_discrete","I2";
;
CDS_LOCATION"C2R15"
PACK_TYPE"0402V"
LOCATION"C2R15"
VALUE"0.1UF"
VOLTAGE"16V"
TOLERANCE"10%"
MATERIAL"X7R"
PART_NUMBER"A36096-030"
SEC"1"
SEC_TYPE"0402V"
CDS_SEC"1"
CDS_LIB"dev_discrete"
BOM_COST"IO_MODULE"
ROOM"IO_MODULE";
"B"
$PN"2"5;
"A"
$PN"1"10;
%"CAP_A"
"1","(2400,1300)","0","dev_discrete","I21";
;
CDS_LOCATION"C2P11"
MATERIAL"X7R"
PART_NUMBER"A36096-030"
PACK_TYPE"0402V"
TOLERANCE"10%"
LOCATION"C2P11"
VALUE"0.1UF"
VOLTAGE"16V"
ROOM"IO_MODULE"
BOM_COST"IO_MODULE"
CDS_LIB"dev_discrete"
CDS_SEC"1"
SEC_TYPE"0402V"
SEC"1";
"B"
$PN"2"5;
"A"
$PN"1"7;
%"CAP_A"
"1","(2050,1300)","0","dev_discrete","I23";
;
CDS_LOCATION"C2P12"
VALUE"0.1UF"
PACK_TYPE"0402V"
PART_NUMBER"A36096-030"
MATERIAL"X7R"
TOLERANCE"10%"
VOLTAGE"16V"
LOCATION"C2P12"
ROOM"IO_MODULE"
BOM_COST"IO_MODULE"
CDS_LIB"dev_discrete"
CDS_SEC"1"
SEC_TYPE"0402V"
SEC"1";
"B"
$PN"2"5;
"A"
$PN"1"7;
%"GND"
"1","(650,2000)","0","mstr_symbols","I24";
;
VOLTAGE"0"
SIZE"1B"
CDS_LIB"mstr_symbols"
BODY_TYPE"PLUMBING"
HDL_POWER"GND";
"A\NAC"3;
%"CAP_A"
"1","(1000,1300)","0","dev_discrete","I25";
;
CDS_LOCATION"C2R17"
PART_NUMBER"A36096-030"
LOCATION"C2R17"
VALUE"0.1UF"
VOLTAGE"16V"
TOLERANCE"10%"
MATERIAL"X7R"
PACK_TYPE"0402V"
ROOM"IO_MODULE"
BOM_COST"IO_MODULE"
CDS_LIB"dev_discrete"
CDS_SEC"1"
$SEC"1";
"B"
$PN"2"5;
"A"
$PN"1"8;
%"SCONN64_H87568002_A"
"1","(150,3025)","0","mstr_sconn","I27";
;
CDS_SEC"1"
CDS_LOCATION"J8E4"
PART_NUMBER"H87568-002"
GROUP"KR"
LOCATION"J8E4"
MATERIAL"CONN"
ROOM"IO_MODULE"
SEC"1"
SEC_TYPE"SMT"
CDS_LIB"mstr_sconn"
PACK_TYPE"SMT";
"IO2"
$PN"2"35;
"IO3"
$PN"3"51;
"IO4"
$PN"4"4;
"IO5"
$PN"5"0;
"IO6"
$PN"6"0;
"IO1"
$PN"1"36;
"IO64"
$PN"64"29;
"IO62"
$PN"62"14;
"IO61"
$PN"61"37;
"IO60"
$PN"60"3;
"IO59"
$PN"59"26;
"IO58"
$PN"58"25;
"IO10"
$PN"10"4;
"IO11"
$PN"11"0;
"IO12"
$PN"12"0;
"IO13"
$PN"13"4;
"IO14"
$PN"14"33;
"IO15"
$PN"15"32;
"IO16"
$PN"16"4;
"IO17"
$PN"17"0;
"IO18"
$PN"18"0;
"IO19"
$PN"19"4;
"IO20"
$PN"20"38;
"IO21"
$PN"21"21;
"IO22"
$PN"22"4;
"IO23"
$PN"23"0;
"IO24"
$PN"24"0;
"IO25"
$PN"25"4;
"IO26"
$PN"26"39;
"IO27"
$PN"27"22;
"IO28"
$PN"28"4;
"IO29"
$PN"29"40;
"IO30"
$PN"30"27;
"IO31"
$PN"31"28;
"IO32"
$PN"32"11;
"IO33"
$PN"33"6;
"IO34"
$PN"34"6;
"IO35"
$PN"35"6;
"IO36"
$PN"36"52;
"IO37"
$PN"37"41;
"IO38"
$PN"38"42;
"IO39"
$PN"39"3;
"IO40"
$PN"40"43;
"IO41"
$PN"41"44;
"IO42"
$PN"42"3;
"IO43"
$PN"43"45;
"IO44"
$PN"44"46;
"IO45"
$PN"45"3;
"IO46"
$PN"46"47;
"IO47"
$PN"47"48;
"IO48"
$PN"48"3;
"IO49"
$PN"49"31;
"IO50"
$PN"50"30;
"IO51"
$PN"51"3;
"IO52"
$PN"52"23;
"IO53"
$PN"53"24;
"IO54"
$PN"54"3;
"IO55"
$PN"55"12;
"IO56"
$PN"56"13;
"IO57"
$PN"57"3;
"IO63"
$PN"63"3;
"IO7"
$PN"7"4;
"IO8"
$PN"8"49;
"IO9"
$PN"9"50;
%"CAP_A"
"1","(2925,1300)","0","dev_discrete","I3";
;
CDS_LOCATION"C2R18"
LOCATION"C2R18"
MATERIAL"X7R"
PART_NUMBER"A36096-030"
PACK_TYPE"0402V"
TOLERANCE"10%"
VOLTAGE"16V"
VALUE"0.1UF"
ROOM"IO_MODULE"
BOM_COST"IO_MODULE"
CDS_LIB"dev_discrete"
CDS_SEC"1"
$SEC"1";
"B"
$PN"2"5;
"A"
$PN"1"10;
%"GND"
"1","(-475,2000)","0","mstr_symbols","I39";
;
HDL_POWER"GND"
BODY_TYPE"PLUMBING"
SIZE"1B"
CDS_LIB"mstr_symbols"
VOLTAGE"0";
"A\NAC"4;
%"CAP_A"
"1","(475,1300)","0","dev_discrete","I40";
;
CDS_LOCATION"C2R16"
PART_NUMBER"A36096-030"
PACK_TYPE"0402V"
MATERIAL"X7R"
TOLERANCE"10%"
VOLTAGE"16V"
VALUE"0.1UF"
LOCATION"C2R16"
ROOM"IO_MODULE"
BOM_COST"IO_MODULE"
CDS_LIB"dev_discrete"
CDS_SEC"1"
$SEC"1";
"B"
$PN"2"5;
"A"
$PN"1"8;
%"CAP"
"1","(-75,1300)","0","mstr_discrete","I41";
;
CDS_SEC"1"
CDS_LOCATION"C2P10"
MATERIAL"X6S"
PACK_TYPE"1206LF"
PART_NUMBER"D38464-005"
TOLERANCE"10%"
VALUE"22UF"
LOCATION"C2P10"
VOLTAGE"16V"
SEC_TYPE"1206LF"
BOM_COST"IO_MODULE"
CDS_LIB"mstr_discrete"
SEC"1"
ROOM"IO_MODULE";
"A"
$PN"1"9;
"B"
$PN"2"5;
%"CAP_A"
"1","(-525,1300)","0","dev_discrete","I53";
;
CDS_LOCATION"C2P16"
PART_NUMBER"A36096-030"
PACK_TYPE"0402V"
TOLERANCE"10%"
VOLTAGE"16V"
LOCATION"C2P16"
VALUE"0.1UF"
MATERIAL"X7R"
ROOM"IO_MODULE"
BOM_COST"IO_MODULE"
CDS_LIB"dev_discrete"
CDS_SEC"1"
$SEC"1";
"B"
$PN"2"5;
"A"
$PN"1"9;
%"CAP_A"
"1","(-950,1300)","0","dev_discrete","I55";
;
CDS_LOCATION"C2P15"
PACK_TYPE"0402V"
MATERIAL"X7R"
TOLERANCE"10%"
VOLTAGE"16V"
VALUE"0.1UF"
LOCATION"C2P15"
PART_NUMBER"A36096-030"
ROOM"IO_MODULE"
BOM_COST"IO_MODULE"
CDS_LIB"dev_discrete"
CDS_SEC"1"
$SEC"1";
"B"
$PN"2"5;
"A"
$PN"1"9;
%"CAP_A"
"1","(-1400,1300)","0","dev_discrete","I56";
;
CDS_LOCATION"C2P14"
VALUE"0.1UF"
VOLTAGE"16V"
TOLERANCE"10%"
LOCATION"C2P14"
PACK_TYPE"0402V"
MATERIAL"X7R"
PART_NUMBER"A36096-030"
ROOM"IO_MODULE"
BOM_COST"IO_MODULE"
CDS_LIB"dev_discrete"
CDS_SEC"1"
$SEC"1";
"B"
$PN"2"5;
"A"
$PN"1"9;
%"CAP_A"
"1","(-1825,1300)","0","dev_discrete","I57";
;
CDS_LOCATION"C2P13"
VOLTAGE"16V"
VALUE"0.1UF"
LOCATION"C2P13"
PACK_TYPE"0402V"
MATERIAL"X7R"
PART_NUMBER"A36096-030"
TOLERANCE"10%"
ROOM"IO_MODULE"
BOM_COST"IO_MODULE"
CDS_LIB"dev_discrete"
CDS_SEC"1"
$SEC"1";
"B"
$PN"2"5;
"A"
$PN"1"9;
%"GND"
"1","(200,775)","0","mstr_symbols","I58";
;
VOLTAGE"0"
SIZE"1B"
CDS_LIB"mstr_symbols"
BODY_TYPE"PLUMBING"
HDL_POWER"GND";
"A\NAC"5;
%"P12V_STBY"
"1","(875,3925)","0","mstr_symbols","I59";
;
VOLTAGE"12.0V"
CDS_LIB"mstr_symbols"
SIZE"1B"
BODY_TYPE"PLUMBING"
HDL_POWER"P12V_STBY";
"G\NAC"6;
%"P12V_STBY"
"1","(2050,1625)","0","mstr_symbols","I60";
;
VOLTAGE"12.0V"
SIZE"1B"
CDS_LIB"mstr_symbols"
BODY_TYPE"PLUMBING"
HDL_POWER"P12V_STBY";
"G\NAC"7;
%"P12V_STBY"
"1","(850,1625)","0","mstr_symbols","I61";
;
VOLTAGE"12.0V"
CDS_LIB"mstr_symbols"
SIZE"1B"
BODY_TYPE"PLUMBING"
HDL_POWER"P12V_STBY";
"G\NAC"8;
%"P12V_STBY"
"1","(-1100,1625)","0","mstr_symbols","I62";
;
VOLTAGE"12.0V"
CDS_LIB"mstr_symbols"
SIZE"1B"
BODY_TYPE"PLUMBING"
HDL_POWER"P12V_STBY";
"G\NAC"9;
%"P12V_STBY"
"1","(3300,1650)","0","mstr_symbols","I63";
;
VOLTAGE"12.0V"
CDS_LIB"mstr_symbols"
SIZE"1B"
BODY_TYPE"PLUMBING"
HDL_POWER"P12V_STBY";
"G\NAC"10;
%"CAP_A"
"2","(3075,2925)","0","dev_discrete","I82";
;
CDS_LOCATION"C8C15"
PART_NUMBER"A36096-030"
VOLTAGE"16V"
PACK_TYPE"0402V"
LOCATION"C8C15"
MATERIAL"X7R"
TOLERANCE"10%"
VALUE"0.1UF"
SEC"1"
SEC_TYPE"0402V"
CDS_SEC"1"
CDS_LIB"dev_discrete";
"A"
$PN"1"15;
"B"
$PN"2"66;
%"CAP_A"
"2","(3075,2600)","0","dev_discrete","I86";
;
CDS_LOCATION"C8C14"
LOCATION"C8C14"
PART_NUMBER"A36096-030"
VALUE"0.1UF"
TOLERANCE"10%"
PACK_TYPE"0402V"
MATERIAL"X7R"
VOLTAGE"16V"
SEC"1"
SEC_TYPE"0402V"
CDS_SEC"1"
CDS_LIB"dev_discrete";
"A"
$PN"1"63;
"B"
$PN"2"62;
%"RES"
"1","(-3250,3950)","0","mstr_discrete","I88";
;
CDS_SEC"1"
CDS_LOCATION"R1R18"
PART_NUMBER"G21796-112"
MATERIAL"CHIP"
WATTAGE"1/16W"
TOLERANCE"1%"
PACK_TYPE"0402"
LOCATION"R1R18"
VALUE"2.21K"
SEC"1"
SEC_TYPE"0402"
CDS_LIB"mstr_discrete";
"B"
$PN"2"56;
"A"
$PN"1"1;
%"RES"
"1","(-3250,3800)","0","mstr_discrete","I89";
;
CDS_SEC"1"
CDS_LOCATION"R1R19"
PART_NUMBER"G21796-112"
MATERIAL"CHIP"
WATTAGE"1/16W"
PACK_TYPE"0402"
TOLERANCE"1%"
LOCATION"R1R19"
VALUE"2.21K"
SEC"1"
SEC_TYPE"0402"
CDS_LIB"mstr_discrete";
"B"
$PN"2"57;
"A"
$PN"1"1;
%"RES"
"1","(-3250,3500)","0","mstr_discrete","I90";
;
CDS_SEC"1"
CDS_LOCATION"R1R21"
PACK_TYPE"0402"
WATTAGE"1/16W"
MATERIAL"CHIP"
TOLERANCE"1%"
PART_NUMBER"G21796-112"
VALUE"2.21K"
LOCATION"R1R21"
CDS_LIB"mstr_discrete"
SEC_TYPE"0402"
SEC"1";
"B"
$PN"2"59;
"A"
$PN"1"1;
%"RES"
"1","(-3250,3650)","0","mstr_discrete","I91";
;
CDS_SEC"1"
CDS_LOCATION"R1R20"
PACK_TYPE"0402"
TOLERANCE"1%"
PART_NUMBER"G21796-112"
VALUE"2.21K"
LOCATION"R1R20"
WATTAGE"1/16W"
MATERIAL"CHIP"
CDS_LIB"mstr_discrete"
SEC_TYPE"0402"
SEC"1";
"B"
$PN"2"58;
"A"
$PN"1"1;
%"RES"
"1","(-3250,2900)","0","mstr_discrete","I92";
;
CDS_SEC"1"
CDS_LOCATION"R1R22"
PACK_TYPE"0402"
TOLERANCE"1%"
MATERIAL"CHIP"
WATTAGE"1/16W"
LOCATION"R1R22"
VALUE"2.21K"
PART_NUMBER"G21796-112"
CDS_LIB"mstr_discrete"
SEC_TYPE"0402"
SEC"1";
"B"
$PN"2"53;
"A"
$PN"1"1;
%"RES"
"1","(-3250,3350)","0","mstr_discrete","I93";
;
CDS_SEC"1"
CDS_LOCATION"R1R16"
PART_NUMBER"G21796-112"
PACK_TYPE"0402"
TOLERANCE"1%"
WATTAGE"1/16W"
MATERIAL"CHIP"
LOCATION"R1R16"
VALUE"2.21K"
CDS_LIB"mstr_discrete"
SEC_TYPE"0402"
SEC"1";
"B"
$PN"2"34;
"A"
$PN"1"1;
%"RES"
"1","(-3250,3200)","0","mstr_discrete","I94";
;
CDS_SEC"1"
CDS_LOCATION"R1R17"
PART_NUMBER"G21796-112"
PACK_TYPE"0402"
TOLERANCE"1%"
MATERIAL"CHIP"
WATTAGE"1/16W"
LOCATION"R1R17"
VALUE"2.21K"
SEC"1"
SEC_TYPE"0402"
CDS_LIB"mstr_discrete";
"B"
$PN"2"55;
"A"
$PN"1"1;
%"RES"
"1","(-3250,3050)","0","mstr_discrete","I95";
;
CDS_SEC"1"
CDS_LOCATION"R1R23"
MATERIAL"CHIP"
TOLERANCE"1%"
LOCATION"R1R23"
VALUE"2.21K"
PART_NUMBER"G21796-112"
PACK_TYPE"0402"
WATTAGE"1/16W"
CDS_LIB"mstr_discrete"
SEC_TYPE"0402"
SEC"1";
"B"
$PN"2"54;
"A"
$PN"1"1;
END.
